# S9S_MB_2U (Grand Teton) — schematic netlist excerpt (pin names and nets, part order shuffled) for the footprints in the layout excerpt that follows; sources: Cadence DE-HDL packaged netlist, KiCad conversion of 03242023_DA0F0TMBIJ0_F0T_Motherboard_J_brd_V01_OCP.brd

Q129  MOSFET_NCH_DUAL  PJT138K IC  pkg SOT363XD  page 146
  S1  = GND
  G1  = GPU_3V3IO_RSVD5_FFU
  D2  = GPU_3V3IO_RSVD5_FFU_ISO
  S2  = GND
  G2  = GPU_3V3IO_RSVD5_FFU_N
  D1  = GPU_3V3IO_RSVD5_FFU_N

C1873  Q_CAP  0.1UF 25V 10% X7R  pkg 0402  page 190 : A = P3V3_AUX ; B = GND

(kicad_pcb
	(version 20260206)
	(generator "pcbnew")
	(generator_version "10.0")
	(general
		(thickness 1.6)
		(legacy_teardrops no)
	)
	(paper "A4")
	(title_block
		(title "03242023_DA0F0TMBIJ0_F0T_Motherboard_J_brd_V01_OCP.brd")
		(comment 1 "Grand Teton / footprints 2146-2147 of 6105")
	)
	(layers
		(0 "F.Cu" signal "TOP")
		(4 "In1.Cu" signal "GND")
		(6 "In2.Cu" signal "IN1")
		(8 "In3.Cu" signal "GND1")
		(10 "In4.Cu" signal "IN2")
		(12 "In5.Cu" signal "GND2")
		(14 "In6.Cu" signal "IN3")
		(16 "In7.Cu" signal "GND3")
		(18 "In8.Cu" signal "VCC")
		(20 "In9.Cu" signal "VCC1")
		(22 "In10.Cu" signal "GND4")
		(24 "In11.Cu" signal "IN4")
		(26 "In12.Cu" signal "GND5")
		(28 "In13.Cu" signal "IN5")
		(30 "In14.Cu" signal "GND6")
		(32 "In15.Cu" signal "IN6")
		(34 "In16.Cu" signal "GND7")
		(2 "B.Cu" signal "BOTTOM")
		(9 "F.Adhes" user "F.Adhesive")
		(11 "B.Adhes" user "B.Adhesive")
		(13 "F.Paste" user "Package Geometry/Pastemask Top")
		(15 "B.Paste" user "Package Geometry/Pastemask Bottom")
		(5 "F.SilkS" user "Ref Des/Silkscreen Top")
		(7 "B.SilkS" user "Ref Des/Silkscreen Bottom")
		(1 "F.Mask" user "Board Geometry/Soldermask Top")
		(3 "B.Mask" user "Board Geometry/Soldermask Bottom")
		(17 "Dwgs.User" user "User.Drawings")
		(19 "Cmts.User" user "User.Comments")
		(21 "Eco1.User" user "User.Eco1")
		(23 "Eco2.User" user "User.Eco2")
		(25 "Edge.Cuts" user "Board Geometry/Outline")
		(27 "Margin" user)
		(31 "F.CrtYd" user "Package Geometry/Place Bound Top")
		(29 "B.CrtYd" user "Package Geometry/Place Bound Bottom")
		(35 "F.Fab" user "Ref Des/Assembly Top")
		(33 "B.Fab" user "Ref Des/Assembly Bottom")
	)
	(footprint ""
		(layer "F.Cu")
		(at 151.56688 -44.351448)
		(property "Reference" "C1873"
			(at 0 0 0)
			(layer "F.SilkS")
			(hide yes)
			(effects
				(font
					(size 1.27 1.27)
				)
			)
		)
		(property "Value" ""
			(at 0 0 0)
			(layer "F.Fab")
			(effects
				(font
					(size 1.27 1.27)
				)
			)
		)
		(duplicate_pad_numbers_are_jumpers no)
		(fp_line
			(start -0.7874 -0.4064)
			(end 0.7874 -0.4064)
			(stroke
				(width 0.1524)
				(type default)
			)
			(layer "F.SilkS")
		)
		(fp_line
			(start -0.7874 0.4064)
			(end -0.7874 -0.4064)
			(stroke
				(width 0.1524)
				(type default)
			)
			(layer "F.SilkS")
		)
		(fp_line
			(start 0.7874 -0.4064)
			(end 0.7874 0.4064)
			(stroke
				(width 0.1524)
				(type default)
			)
			(layer "F.SilkS")
		)
		(fp_line
			(start 0.7874 0.4064)
			(end -0.7874 0.4064)
			(stroke
				(width 0.1524)
				(type default)
			)
			(layer "F.SilkS")
		)
		(fp_line
			(start -0.67945 -0.305054)
			(end -0.12065 -0.305054)
			(stroke
				(width 0.1)
				(type default)
			)
			(layer "F.Fab")
		)
		(fp_line
			(start -0.67945 0.3048)
			(end -0.67945 -0.305054)
			(stroke
				(width 0.1)
				(type default)
			)
			(layer "F.Fab")
		)
		(fp_line
			(start -0.12065 -0.305054)
			(end -0.12065 -0.2794)
			(stroke
				(width 0.1)
				(type default)
			)
			(layer "F.Fab")
		)
		(fp_line
			(start -0.12065 -0.2794)
			(end 0.12065 -0.2794)
			(stroke
				(width 0.1)
				(type default)
			)
			(layer "F.Fab")
		)
		(fp_line
			(start -0.12065 0.2794)
			(end -0.12065 0.3048)
			(stroke
				(width 0.1)
				(type default)
			)
			(layer "F.Fab")
		)
		(fp_line
			(start -0.12065 0.3048)
			(end -0.67945 0.3048)
			(stroke
				(width 0.1)
				(type default)
			)
			(layer "F.Fab")
		)
		(fp_line
			(start 0.120396 0.2794)
			(end -0.12065 0.2794)
			(stroke
				(width 0.1)
				(type default)
			)
			(layer "F.Fab")
		)
		(fp_line
			(start 0.120396 0.3048)
			(end 0.120396 0.2794)
			(stroke
				(width 0.1)
				(type default)
			)
			(layer "F.Fab")
		)
		(fp_line
			(start 0.12065 -0.3048)
			(end 0.67945 -0.3048)
			(stroke
				(width 0.1)
				(type default)
			)
			(layer "F.Fab")
		)
		(fp_line
			(start 0.12065 -0.2794)
			(end 0.12065 -0.3048)
			(stroke
				(width 0.1)
				(type default)
			)
			(layer "F.Fab")
		)
		(fp_line
			(start 0.67945 -0.3048)
			(end 0.67945 0.3048)
			(stroke
				(width 0.1)
				(type default)
			)
			(layer "F.Fab")
		)
		(fp_line
			(start 0.67945 0.3048)
			(end 0.120396 0.3048)
			(stroke
				(width 0.1)
				(type default)
			)
			(layer "F.Fab")
		)
		(pad "1" smd circle
			(at -0.40005 0)
			(size 0 0)
			(layers "F.Cu" "F.Mask" "F.Paste")
			(net "P3V3_AUX")
		)
		(pad "2" smd circle
			(at 0.40005 0)
			(size 0 0)
			(layers "F.Cu" "F.Mask" "F.Paste")
			(net "GND")
		)
	)
	(footprint ""
		(layer "F.Cu")
		(at 297.74642 -424.00601 90)
		(property "Reference" "Q129"
			(at -7.70382 9.049512 90)
			(unlocked yes)
			(layer "F.SilkS")
			(effects
				(font
					(size 0.7874 0.5842)
					(thickness 0.1524)
				)
				(justify left)
			)
		)
		(property "Value" ""
			(at 0 0 90)
			(layer "F.Fab")
			(effects
				(font
					(size 1.27 1.27)
				)
			)
		)
		(duplicate_pad_numbers_are_jumpers no)
		(fp_line
			(start 1.332738 -1.100074)
			(end 1.332738 1.100074)
			(stroke
				(width 0.1524)
				(type default)
			)
			(layer "F.SilkS")
		)
		(fp_line
			(start 0.4826 -1.100074)
			(end 1.332738 -1.100074)
			(stroke
				(width 0.1524)
				(type default)
			)
			(layer "F.SilkS")
		)
		(fp_line
			(start -0.4826 -1.100074)
			(end 0 -0.541274)
			(stroke
				(width 0.1524)
				(type default)
			)
			(layer "F.SilkS")
		)
		(fp_line
			(start -1.332738 -1.100074)
			(end -0.4826 -1.100074)
			(stroke
				(width 0.1524)
				(type default)
			)
			(layer "F.SilkS")
		)
		(fp_line
			(start 0 -0.541274)
			(end 0.4826 -1.100074)
			(stroke
				(width 0.1524)
				(type default)
			)
			(layer "F.SilkS")
		)
		(fp_line
			(start 1.332738 1.100074)
			(end -1.332738 1.100074)
			(stroke
				(width 0.1524)
				(type default)
			)
			(layer "F.SilkS")
		)
		(fp_line
			(start -1.332738 1.100074)
			(end -1.332738 -1.100074)
			(stroke
				(width 0.1524)
				(type default)
			)
			(layer "F.SilkS")
		)
		(fp_poly
			(pts
				(xy -2.25552 -1.425194) (xy -1.553464 -1.074166) (xy -2.25552 -0.723138)
			)
			(stroke
				(width 0)
				(type default)
			)
			(fill yes)
			(layer "F.SilkS")
		)
		(fp_line
			(start 0.674878 -1.100074)
			(end 0.674878 1.100074)
			(stroke
				(width 0.1)
				(type default)
			)
			(layer "F.Fab")
		)
		(fp_line
			(start -0.674878 -1.100074)
			(end 0.674878 -1.100074)
			(stroke
				(width 0.1)
				(type default)
			)
			(layer "F.Fab")
		)
		(fp_line
			(start 0.674878 1.100074)
			(end -0.674878 1.100074)
			(stroke
				(width 0.1)
				(type default)
			)
			(layer "F.Fab")
		)
		(fp_line
			(start -0.674878 1.100074)
			(end -0.674878 -1.100074)
			(stroke
				(width 0.1)
				(type default)
			)
			(layer "F.Fab")
		)
		(fp_poly
			(pts
				(xy -2.2352 -0.298958) (xy -2.2352 -1.001014) (xy -1.533144 -0.649986)
			)
			(stroke
				(width 0)
				(type default)
			)
			(fill yes)
			(layer "F.Fab")
		)
		(pad "1" smd rect
			(at -0.94996 -0.649986 180)
			(size 0.4318 0.508)
			(layers "F.Cu" "F.Mask" "F.Paste")
			(net "GND")
		)
		(pad "2" smd rect
			(at -0.94996 0 180)
			(size 0.4318 0.508)
			(layers "F.Cu" "F.Mask" "F.Paste")
			(net "GPU_3V3IO_RSVD5_FFU")
		)
		(pad "3" smd rect
			(at -0.94996 0.649986 180)
			(size 0.4318 0.508)
			(layers "F.Cu" "F.Mask" "F.Paste")
			(net "GPU_3V3IO_RSVD5_FFU_ISO")
		)
		(pad "4" smd rect
			(at 0.94996 0.649986 180)
			(size 0.4318 0.508)
			(layers "F.Cu" "F.Mask" "F.Paste")
			(net "GND")
		)
		(pad "5" smd rect
			(at 0.94996 0 180)
			(size 0.4318 0.508)
			(layers "F.Cu" "F.Mask" "F.Paste")
			(net "GPU_3V3IO_RSVD5_FFU_N")
		)
		(pad "6" smd rect
			(at 0.94996 -0.649986 180)
			(size 0.4318 0.508)
			(layers "F.Cu" "F.Mask" "F.Paste")
			(net "GPU_3V3IO_RSVD5_FFU_N")
		)
	)
)
